# BASEBOARD_FAB2 (Tioga Pass) — schematic netlist excerpt (pin names and nets, part order shuffled) for the footprints in the layout excerpt that follows; sources: Cadence DE-HDL packaged netlist, KiCad conversion of Wiwynn_Tioga_Pass_MB.brd

C25W78  CAP  100.0PF 50V 5% COG  pkg 0402LF  page 252 : A = V_IBMC_5V_DDC_SCL_J ; B = GND
R32W3  RES  3.3K 5% CHIP  pkg 0402  page 185 : A = VREF_LMV431_1V42 ; B = GND
C5M12  CAP  100UF 4V 20% X5R  pkg 0805  page 220 : A = PVDDQ_DEF ; B = GND

(kicad_pcb
	(version 20260206)
	(generator "pcbnew")
	(generator_version "10.0")
	(general
		(thickness 1.6)
		(legacy_teardrops no)
	)
	(paper "A4")
	(title_block
		(title "Wiwynn_Tioga_Pass_MB.brd")
		(comment 1 "Tioga Pass / footprints 3308-3310 of 4770")
	)
	(layers
		(0 "F.Cu" signal "TOP")
		(4 "In1.Cu" signal "L2GND")
		(6 "In2.Cu" signal "L3")
		(8 "In3.Cu" signal "L4GND")
		(10 "In4.Cu" signal "L5")
		(12 "In5.Cu" signal "L6GND")
		(14 "In6.Cu" signal "L7VCC")
		(16 "In7.Cu" signal "L8VCC")
		(18 "In8.Cu" signal "L9GND")
		(20 "In9.Cu" signal "L10")
		(22 "In10.Cu" signal "L11GND")
		(24 "In11.Cu" signal "L12")
		(26 "In12.Cu" signal "L13GND")
		(2 "B.Cu" signal "BOTTOM")
		(9 "F.Adhes" user "F.Adhesive")
		(11 "B.Adhes" user "B.Adhesive")
		(13 "F.Paste" user "Package Geometry/Pastemask Top")
		(15 "B.Paste" user "Package Geometry/Pastemask Bottom")
		(5 "F.SilkS" user "Ref Des/Silkscreen Top")
		(7 "B.SilkS" user "Ref Des/Silkscreen Bottom")
		(1 "F.Mask" user "Board Geometry/Soldermask Top")
		(3 "B.Mask" user "Board Geometry/Soldermask Bottom")
		(17 "Dwgs.User" user "User.Drawings")
		(19 "Cmts.User" user "User.Comments")
		(21 "Eco1.User" user "User.Eco1")
		(23 "Eco2.User" user "User.Eco2")
		(25 "Edge.Cuts" user "Board Geometry/Outline")
		(27 "Margin" user)
		(31 "F.CrtYd" user "Package Geometry/Place Bound Top")
		(29 "B.CrtYd" user "Package Geometry/Place Bound Bottom")
		(35 "F.Fab" user "Ref Des/Assembly Top")
		(33 "B.Fab" user "Ref Des/Assembly Bottom")
	)
	(footprint ""
		(layer "B.Cu")
		(at 266.3952 -126.0348 -90)
		(property "Reference" "C5M12"
			(at 0 0 90)
			(layer "B.SilkS")
			(hide yes)
			(effects
				(font
					(size 1.27 1.27)
				)
				(justify mirror)
			)
		)
		(property "Value" ""
			(at 0 0 90)
			(layer "B.Fab")
			(effects
				(font
					(size 1.27 1.27)
				)
				(justify mirror)
			)
		)
		(duplicate_pad_numbers_are_jumpers no)
		(fp_rect
			(start 0.7239 1.9939)
			(end -0.7239 -0.2159)
			(stroke
				(width 0)
				(type default)
			)
			(fill no)
			(layer "B.CrtYd")
		)
		(fp_line
			(start -0.7239 1.9939)
			(end -0.7239 -0.2159)
			(stroke
				(width 0.1)
				(type default)
			)
			(layer "B.Fab")
		)
		(fp_line
			(start 0.7239 1.9939)
			(end -0.7239 1.9939)
			(stroke
				(width 0.1)
				(type default)
			)
			(layer "B.Fab")
		)
		(fp_line
			(start -0.7239 -0.2159)
			(end 0.7239 -0.2159)
			(stroke
				(width 0.1)
				(type default)
			)
			(layer "B.Fab")
		)
		(fp_line
			(start 0.7239 -0.2159)
			(end 0.7239 1.9939)
			(stroke
				(width 0.1)
				(type default)
			)
			(layer "B.Fab")
		)
		(pad "1" smd rect
			(at 0 0 90)
			(size 1.27 1.016)
			(layers "B.Cu" "B.Mask" "B.Paste")
			(net "PVDDQ_DEF")
		)
		(pad "2" smd rect
			(at 0 1.778 90)
			(size 1.27 1.016)
			(layers "B.Cu" "B.Mask" "B.Paste")
			(net "GND")
		)
		(zone
			(layer "B.Cu")
			(hatch none 0.5)
			(connect_pads
				(clearance 0)
			)
			(min_thickness 0.25)
			(keepout
				(tracks not_allowed)
				(vias allowed)
				(pads allowed)
				(copperpour not_allowed)
				(footprints allowed)
			)
			(placement
				(enabled no)
				(sheetname "")
			)
			(fill
				(thermal_gap 0.5)
				(thermal_bridge_width 0.5)
				(island_removal_mode 0)
			)
			(polygon
				(pts
					(xy 265.1252 -125.3998) (xy 265.8872 -125.3998) (xy 265.8872 -126.6698) (xy 265.1252 -126.6698)
				)
			)
		)
	)
	(footprint ""
		(layer "B.Cu")
		(at 494.712244 -49.154588 180)
		(property "Reference" "C25W78"
			(at 0.8382 -0.67818 180)
			(unlocked yes)
			(layer "B.SilkS")
			(effects
				(font
					(size 0.4064 0.254)
					(thickness 0.1524)
				)
				(justify left mirror)
			)
		)
		(property "Value" ""
			(at 0 0 0)
			(layer "B.Fab")
			(effects
				(font
					(size 1.27 1.27)
				)
				(justify mirror)
			)
		)
		(duplicate_pad_numbers_are_jumpers no)
		(fp_poly
			(pts
				(xy -0.3048 -0.1016) (xy -0.3048 0.9906) (xy 0.3048 0.9906) (xy 0.3048 -0.1016)
			)
			(stroke
				(width 0)
				(type default)
			)
			(fill no)
			(layer "B.CrtYd")
		)
		(fp_line
			(start 0.3048 0.9906)
			(end -0.3048 0.9906)
			(stroke
				(width 0.1)
				(type default)
			)
			(layer "B.Fab")
		)
		(fp_line
			(start 0.3048 -0.1016)
			(end 0.3048 0.9906)
			(stroke
				(width 0.1)
				(type default)
			)
			(layer "B.Fab")
		)
		(fp_line
			(start -0.3048 0.9906)
			(end -0.3048 -0.1016)
			(stroke
				(width 0.1)
				(type default)
			)
			(layer "B.Fab")
		)
		(fp_line
			(start -0.3048 -0.1016)
			(end 0.3048 -0.1016)
			(stroke
				(width 0.1)
				(type default)
			)
			(layer "B.Fab")
		)
		(pad "1" smd rect
			(at 0 0)
			(size 0.508 0.508)
			(layers "B.Cu" "B.Mask" "B.Paste")
			(net "V_IBMC_5V_DDC_SCL_J")
		)
		(pad "2" smd rect
			(at 0 0.889)
			(size 0.508 0.508)
			(layers "B.Cu" "B.Mask" "B.Paste")
			(net "GND")
		)
		(zone
			(layer "B.Cu")
			(hatch none 0.5)
			(connect_pads
				(clearance 0)
			)
			(min_thickness 0.25)
			(keepout
				(tracks not_allowed)
				(vias allowed)
				(pads allowed)
				(copperpour not_allowed)
				(footprints allowed)
			)
			(placement
				(enabled no)
				(sheetname "")
			)
			(fill
				(thermal_gap 0.5)
				(thermal_bridge_width 0.5)
				(island_removal_mode 0)
			)
			(polygon
				(pts
					(xy 494.458244 -49.789588) (xy 494.966244 -49.789588) (xy 494.966244 -49.408588) (xy 494.458244 -49.408588)
				)
			)
		)
		(zone
			(layer "B.Cu")
			(hatch none 0.5)
			(connect_pads
				(clearance 0)
			)
			(min_thickness 0.25)
			(keepout
				(tracks allowed)
				(vias not_allowed)
				(pads allowed)
				(copperpour not_allowed)
				(footprints allowed)
			)
			(placement
				(enabled no)
				(sheetname "")
			)
			(fill
				(thermal_gap 0.5)
				(thermal_bridge_width 0.5)
				(island_removal_mode 0)
			)
			(polygon
				(pts
					(xy 494.458244 -49.408588) (xy 494.966244 -49.408588) (xy 494.966244 -49.789588) (xy 494.458244 -49.789588)
				)
			)
		)
	)
	(footprint ""
		(layer "B.Cu")
		(at 395.0843 -20.6248 90)
		(property "Reference" "R32W3"
			(at 0.8382 -0.67818 90)
			(unlocked yes)
			(layer "B.SilkS")
			(effects
				(font
					(size 0.4064 0.254)
					(thickness 0.1524)
				)
				(justify left mirror)
			)
		)
		(property "Value" ""
			(at 0 0 90)
			(layer "B.Fab")
			(effects
				(font
					(size 1.27 1.27)
				)
				(justify mirror)
			)
		)
		(duplicate_pad_numbers_are_jumpers no)
		(fp_poly
			(pts
				(xy 0.2794 -0.1016) (xy -0.2794 -0.1016) (xy -0.2794 0.9906) (xy 0.2794 0.9906)
			)
			(stroke
				(width 0)
				(type default)
			)
			(fill no)
			(layer "B.CrtYd")
		)
		(fp_line
			(start 0.2794 -0.1016)
			(end 0.2794 0.9906)
			(stroke
				(width 0.1)
				(type default)
			)
			(layer "B.Fab")
		)
		(fp_line
			(start -0.2794 -0.1016)
			(end 0.2794 -0.1016)
			(stroke
				(width 0.1)
				(type default)
			)
			(layer "B.Fab")
		)
		(fp_line
			(start 0.2794 0.9906)
			(end -0.2794 0.9906)
			(stroke
				(width 0.1)
				(type default)
			)
			(layer "B.Fab")
		)
		(fp_line
			(start -0.2794 0.9906)
			(end -0.2794 -0.1016)
			(stroke
				(width 0.1)
				(type default)
			)
			(layer "B.Fab")
		)
		(pad "1" smd rect
			(at 0 0 270)
			(size 0.508 0.508)
			(layers "B.Cu" "B.Mask" "B.Paste")
			(net "VREF_LMV431_1V42")
		)
		(pad "2" smd rect
			(at 0 0.889 270)
			(size 0.508 0.508)
			(layers "B.Cu" "B.Mask" "B.Paste")
			(net "GND")
		)
		(zone
			(layer "B.Cu")
			(hatch none 0.5)
			(connect_pads
				(clearance 0)
			)
			(min_thickness 0.25)
			(keepout
				(tracks allowed)
				(vias not_allowed)
				(pads allowed)
				(copperpour not_allowed)
				(footprints allowed)
			)
			(placement
				(enabled no)
				(sheetname "")
			)
			(fill
				(thermal_gap 0.5)
				(thermal_bridge_width 0.5)
				(island_removal_mode 0)
			)
			(polygon
				(pts
					(xy 395.3383 -20.8788) (xy 395.3383 -20.3708) (xy 395.7193 -20.3708) (xy 395.7193 -20.8788)
				)
			)
		)
		(zone
			(layer "B.Cu")
			(hatch none 0.5)
			(connect_pads
				(clearance 0)
			)
			(min_thickness 0.25)
			(keepout
				(tracks not_allowed)
				(vias allowed)
				(pads allowed)
				(copperpour not_allowed)
				(footprints allowed)
			)
			(placement
				(enabled no)
				(sheetname "")
			)
			(fill
				(thermal_gap 0.5)
				(thermal_bridge_width 0.5)
				(island_removal_mode 0)
			)
			(polygon
				(pts
					(xy 395.7193 -20.8788) (xy 395.7193 -20.3708) (xy 395.3383 -20.3708) (xy 395.3383 -20.8788)
				)
			)
		)
	)
)
